# S9S_MB_2U (Grand Teton) — schematic netlist excerpt (pin names and nets, part order shuffled) for the footprints in the layout excerpt that follows; sources: Cadence DE-HDL packaged netlist, KiCad conversion of 03242023_DA0F0TMBIJ0_F0T_Motherboard_J_brd_V01_OCP.brd

PC481_P1_8  Q_CAP  2.2UF 10V 10% X6S  pkg C0402  page 288 : A = PVCCIN_CPU1_PVCC ; B = GND
R4730  Q_RES  10K 1% CHIP  pkg 0402LF  page 144 : A = P3V3_AUX ; B = PRSNT_CABLE_SWB_B2_N

(kicad_pcb
	(version 20260206)
	(generator "pcbnew")
	(generator_version "10.0")
	(general
		(thickness 1.6)
		(legacy_teardrops no)
	)
	(paper "A4")
	(title_block
		(title "03242023_DA0F0TMBIJ0_F0T_Motherboard_J_brd_V01_OCP.brd")
		(comment 1 "Grand Teton / footprints 2028-2029 of 6105")
	)
	(layers
		(0 "F.Cu" signal "TOP")
		(4 "In1.Cu" signal "GND")
		(6 "In2.Cu" signal "IN1")
		(8 "In3.Cu" signal "GND1")
		(10 "In4.Cu" signal "IN2")
		(12 "In5.Cu" signal "GND2")
		(14 "In6.Cu" signal "IN3")
		(16 "In7.Cu" signal "GND3")
		(18 "In8.Cu" signal "VCC")
		(20 "In9.Cu" signal "VCC1")
		(22 "In10.Cu" signal "GND4")
		(24 "In11.Cu" signal "IN4")
		(26 "In12.Cu" signal "GND5")
		(28 "In13.Cu" signal "IN5")
		(30 "In14.Cu" signal "GND6")
		(32 "In15.Cu" signal "IN6")
		(34 "In16.Cu" signal "GND7")
		(2 "B.Cu" signal "BOTTOM")
		(9 "F.Adhes" user "F.Adhesive")
		(11 "B.Adhes" user "B.Adhesive")
		(13 "F.Paste" user "Package Geometry/Pastemask Top")
		(15 "B.Paste" user "Package Geometry/Pastemask Bottom")
		(5 "F.SilkS" user "Ref Des/Silkscreen Top")
		(7 "B.SilkS" user "Ref Des/Silkscreen Bottom")
		(1 "F.Mask" user "Board Geometry/Soldermask Top")
		(3 "B.Mask" user "Board Geometry/Soldermask Bottom")
		(17 "Dwgs.User" user "User.Drawings")
		(19 "Cmts.User" user "User.Comments")
		(21 "Eco1.User" user "User.Eco1")
		(23 "Eco2.User" user "User.Eco2")
		(25 "Edge.Cuts" user "Board Geometry/Outline")
		(27 "Margin" user)
		(31 "F.CrtYd" user "Package Geometry/Place Bound Top")
		(29 "B.CrtYd" user "Package Geometry/Place Bound Bottom")
		(35 "F.Fab" user "Ref Des/Assembly Top")
		(33 "B.Fab" user "Ref Des/Assembly Bottom")
	)
	(footprint ""
		(layer "F.Cu")
		(at 355.8286 -403.9108)
		(property "Reference" "R4730"
			(at 0 0 0)
			(layer "F.SilkS")
			(hide yes)
			(effects
				(font
					(size 1.27 1.27)
				)
			)
		)
		(property "Value" ""
			(at 0 0 0)
			(layer "F.Fab")
			(effects
				(font
					(size 1.27 1.27)
				)
			)
		)
		(duplicate_pad_numbers_are_jumpers no)
		(fp_line
			(start -0.7874 -0.4064)
			(end 0.7874 -0.4064)
			(stroke
				(width 0.1524)
				(type default)
			)
			(layer "F.SilkS")
		)
		(fp_line
			(start -0.7874 0.4064)
			(end -0.7874 -0.4064)
			(stroke
				(width 0.1524)
				(type default)
			)
			(layer "F.SilkS")
		)
		(fp_line
			(start 0.7874 -0.4064)
			(end 0.7874 0.4064)
			(stroke
				(width 0.1524)
				(type default)
			)
			(layer "F.SilkS")
		)
		(fp_line
			(start 0.7874 0.4064)
			(end -0.7874 0.4064)
			(stroke
				(width 0.1524)
				(type default)
			)
			(layer "F.SilkS")
		)
		(fp_line
			(start -0.67945 -0.305054)
			(end -0.12065 -0.305054)
			(stroke
				(width 0.1)
				(type default)
			)
			(layer "F.Fab")
		)
		(fp_line
			(start -0.67945 0.3048)
			(end -0.67945 -0.305054)
			(stroke
				(width 0.1)
				(type default)
			)
			(layer "F.Fab")
		)
		(fp_line
			(start -0.12065 -0.305054)
			(end -0.12065 -0.2794)
			(stroke
				(width 0.1)
				(type default)
			)
			(layer "F.Fab")
		)
		(fp_line
			(start -0.12065 -0.2794)
			(end 0.12065 -0.2794)
			(stroke
				(width 0.1)
				(type default)
			)
			(layer "F.Fab")
		)
		(fp_line
			(start -0.12065 0.2794)
			(end -0.12065 0.3048)
			(stroke
				(width 0.1)
				(type default)
			)
			(layer "F.Fab")
		)
		(fp_line
			(start -0.12065 0.3048)
			(end -0.67945 0.3048)
			(stroke
				(width 0.1)
				(type default)
			)
			(layer "F.Fab")
		)
		(fp_line
			(start 0.120396 0.2794)
			(end -0.12065 0.2794)
			(stroke
				(width 0.1)
				(type default)
			)
			(layer "F.Fab")
		)
		(fp_line
			(start 0.120396 0.3048)
			(end 0.120396 0.2794)
			(stroke
				(width 0.1)
				(type default)
			)
			(layer "F.Fab")
		)
		(fp_line
			(start 0.12065 -0.3048)
			(end 0.67945 -0.3048)
			(stroke
				(width 0.1)
				(type default)
			)
			(layer "F.Fab")
		)
		(fp_line
			(start 0.12065 -0.2794)
			(end 0.12065 -0.3048)
			(stroke
				(width 0.1)
				(type default)
			)
			(layer "F.Fab")
		)
		(fp_line
			(start 0.67945 -0.3048)
			(end 0.67945 0.3048)
			(stroke
				(width 0.1)
				(type default)
			)
			(layer "F.Fab")
		)
		(fp_line
			(start 0.67945 0.3048)
			(end 0.120396 0.3048)
			(stroke
				(width 0.1)
				(type default)
			)
			(layer "F.Fab")
		)
		(pad "1" smd circle
			(at -0.40005 0)
			(size 0 0)
			(layers "F.Cu" "F.Mask" "F.Paste")
			(net "P3V3_AUX")
		)
		(pad "2" smd circle
			(at 0.40005 0)
			(size 0 0)
			(layers "F.Cu" "F.Mask" "F.Paste")
			(net "PRSNT_CABLE_SWB_B2_N")
		)
	)
	(footprint ""
		(layer "F.Cu")
		(at 134.225538 -342.726264 -90)
		(property "Reference" "PC481_P1_8"
			(at 0 0 270)
			(layer "F.SilkS")
			(hide yes)
			(effects
				(font
					(size 1.27 1.27)
				)
			)
		)
		(property "Value" ""
			(at 0 0 270)
			(layer "F.Fab")
			(effects
				(font
					(size 1.27 1.27)
				)
			)
		)
		(duplicate_pad_numbers_are_jumpers no)
		(fp_line
			(start -0.7874 0.4064)
			(end -0.7874 -0.4064)
			(stroke
				(width 0.1524)
				(type default)
			)
			(layer "F.SilkS")
		)
		(fp_line
			(start 0.7874 0.4064)
			(end -0.7874 0.4064)
			(stroke
				(width 0.1524)
				(type default)
			)
			(layer "F.SilkS")
		)
		(fp_line
			(start -0.7874 -0.4064)
			(end 0.7874 -0.4064)
			(stroke
				(width 0.1524)
				(type default)
			)
			(layer "F.SilkS")
		)
		(fp_line
			(start 0.7874 -0.4064)
			(end 0.7874 0.4064)
			(stroke
				(width 0.1524)
				(type default)
			)
			(layer "F.SilkS")
		)
		(fp_line
			(start -0.67945 0.3048)
			(end -0.67945 -0.305054)
			(stroke
				(width 0.1)
				(type default)
			)
			(layer "F.Fab")
		)
		(fp_line
			(start -0.12065 0.3048)
			(end -0.67945 0.3048)
			(stroke
				(width 0.1)
				(type default)
			)
			(layer "F.Fab")
		)
		(fp_line
			(start 0.120396 0.3048)
			(end 0.120396 0.2794)
			(stroke
				(width 0.1)
				(type default)
			)
			(layer "F.Fab")
		)
		(fp_line
			(start 0.67945 0.3048)
			(end 0.120396 0.3048)
			(stroke
				(width 0.1)
				(type default)
			)
			(layer "F.Fab")
		)
		(fp_line
			(start -0.12065 0.2794)
			(end -0.12065 0.3048)
			(stroke
				(width 0.1)
				(type default)
			)
			(layer "F.Fab")
		)
		(fp_line
			(start 0.120396 0.2794)
			(end -0.12065 0.2794)
			(stroke
				(width 0.1)
				(type default)
			)
			(layer "F.Fab")
		)
		(fp_line
			(start -0.12065 -0.2794)
			(end 0.12065 -0.2794)
			(stroke
				(width 0.1)
				(type default)
			)
			(layer "F.Fab")
		)
		(fp_line
			(start 0.12065 -0.2794)
			(end 0.12065 -0.3048)
			(stroke
				(width 0.1)
				(type default)
			)
			(layer "F.Fab")
		)
		(fp_line
			(start 0.12065 -0.3048)
			(end 0.67945 -0.3048)
			(stroke
				(width 0.1)
				(type default)
			)
			(layer "F.Fab")
		)
		(fp_line
			(start 0.67945 -0.3048)
			(end 0.67945 0.3048)
			(stroke
				(width 0.1)
				(type default)
			)
			(layer "F.Fab")
		)
		(fp_line
			(start -0.67945 -0.305054)
			(end -0.12065 -0.305054)
			(stroke
				(width 0.1)
				(type default)
			)
			(layer "F.Fab")
		)
		(fp_line
			(start -0.12065 -0.305054)
			(end -0.12065 -0.2794)
			(stroke
				(width 0.1)
				(type default)
			)
			(layer "F.Fab")
		)
		(pad "1" smd circle
			(at -0.40005 0 270)
			(size 0 0)
			(layers "F.Cu" "F.Mask" "F.Paste")
			(net "PVCCIN_CPU1_PVCC")
		)
		(pad "2" smd circle
			(at 0.40005 0 270)
			(size 0 0)
			(layers "F.Cu" "F.Mask" "F.Paste")
			(net "GND")
		)
	)
)
